# BASEBOARD_FAB2 (Tioga Pass) — schematic netlist excerpt (pin names and nets, part order shuffled) for the footprints in the layout excerpt that follows; sources: Cadence DE-HDL packaged netlist, KiCad conversion of Wiwynn_Tioga_Pass_MB.brd

CT35  CAP  1000PF 50V 10% X7R  pkg 0402LF  page 204 : A = VR_PVCCIN_CPU0_PHASE5 ; B = VR_PVCCIN_CPU0_PHASE5_RC
R6W26  RES  10.0 1% CHIP  pkg 0402  page 248 : A = SMB_CPU0_PE_HP_GTL_SCL ; B = SMB_CPU0_PE_HP_GTL_R_SCL
R7F1  RES  10.0K 1% CHIP  pkg 0402  page 241 : A = VR_P5V_STBY_VSENSE_R ; B = VR_P5V_STBY_VSENSE

(kicad_pcb
	(version 20260206)
	(generator "pcbnew")
	(generator_version "10.0")
	(general
		(thickness 1.6)
		(legacy_teardrops no)
	)
	(paper "A4")
	(title_block
		(title "Wiwynn_Tioga_Pass_MB.brd")
		(comment 1 "Tioga Pass / footprints 72-74 of 4770")
	)
	(layers
		(0 "F.Cu" signal "TOP")
		(4 "In1.Cu" signal "L2GND")
		(6 "In2.Cu" signal "L3")
		(8 "In3.Cu" signal "L4GND")
		(10 "In4.Cu" signal "L5")
		(12 "In5.Cu" signal "L6GND")
		(14 "In6.Cu" signal "L7VCC")
		(16 "In7.Cu" signal "L8VCC")
		(18 "In8.Cu" signal "L9GND")
		(20 "In9.Cu" signal "L10")
		(22 "In10.Cu" signal "L11GND")
		(24 "In11.Cu" signal "L12")
		(26 "In12.Cu" signal "L13GND")
		(2 "B.Cu" signal "BOTTOM")
		(9 "F.Adhes" user "F.Adhesive")
		(11 "B.Adhes" user "B.Adhesive")
		(13 "F.Paste" user "Package Geometry/Pastemask Top")
		(15 "B.Paste" user "Package Geometry/Pastemask Bottom")
		(5 "F.SilkS" user "Ref Des/Silkscreen Top")
		(7 "B.SilkS" user "Ref Des/Silkscreen Bottom")
		(1 "F.Mask" user "Board Geometry/Soldermask Top")
		(3 "B.Mask" user "Board Geometry/Soldermask Bottom")
		(17 "Dwgs.User" user "User.Drawings")
		(19 "Cmts.User" user "User.Comments")
		(21 "Eco1.User" user "User.Eco1")
		(23 "Eco2.User" user "User.Eco2")
		(25 "Edge.Cuts" user "Board Geometry/Outline")
		(27 "Margin" user)
		(31 "F.CrtYd" user "Package Geometry/Place Bound Top")
		(29 "B.CrtYd" user "Package Geometry/Place Bound Bottom")
		(35 "F.Fab" user "Ref Des/Assembly Top")
		(33 "B.Fab" user "Ref Des/Assembly Bottom")
	)
	(footprint ""
		(layer "F.Cu")
		(at 390.398 -63.6905 180)
		(property "Reference" "R7F1"
			(at 0 0 180)
			(layer "F.SilkS")
			(hide yes)
			(effects
				(font
					(size 1.27 1.27)
				)
			)
		)
		(property "Value" ""
			(at 0 0 180)
			(layer "F.Fab")
			(effects
				(font
					(size 1.27 1.27)
				)
			)
		)
		(duplicate_pad_numbers_are_jumpers no)
		(fp_poly
			(pts
				(xy -0.2794 -0.1016) (xy 0.2794 -0.1016) (xy 0.2794 0.9906) (xy -0.2794 0.9906)
			)
			(stroke
				(width 0)
				(type default)
			)
			(fill no)
			(layer "F.CrtYd")
		)
		(fp_line
			(start 0.2794 0.9906)
			(end 0.2794 -0.1016)
			(stroke
				(width 0.1)
				(type default)
			)
			(layer "F.Fab")
		)
		(fp_line
			(start 0.2794 -0.1016)
			(end -0.2794 -0.1016)
			(stroke
				(width 0.1)
				(type default)
			)
			(layer "F.Fab")
		)
		(fp_line
			(start -0.2794 0.9906)
			(end 0.2794 0.9906)
			(stroke
				(width 0.1)
				(type default)
			)
			(layer "F.Fab")
		)
		(fp_line
			(start -0.2794 -0.1016)
			(end -0.2794 0.9906)
			(stroke
				(width 0.1)
				(type default)
			)
			(layer "F.Fab")
		)
		(pad "1" smd rect
			(at 0 0 180)
			(size 0.508 0.508)
			(layers "F.Cu" "F.Mask" "F.Paste")
			(net "VR_P5V_STBY_VSENSE_R")
		)
		(pad "2" smd rect
			(at 0 0.889 180)
			(size 0.508 0.508)
			(layers "F.Cu" "F.Mask" "F.Paste")
			(net "VR_P5V_STBY_VSENSE")
		)
		(zone
			(layer "F.Cu")
			(hatch none 0.5)
			(connect_pads
				(clearance 0)
			)
			(min_thickness 0.25)
			(keepout
				(tracks not_allowed)
				(vias allowed)
				(pads allowed)
				(copperpour not_allowed)
				(footprints allowed)
			)
			(placement
				(enabled no)
				(sheetname "")
			)
			(fill
				(thermal_gap 0.5)
				(thermal_bridge_width 0.5)
				(island_removal_mode 0)
			)
			(polygon
				(pts
					(xy 390.652 -64.3255) (xy 390.144 -64.3255) (xy 390.144 -63.9445) (xy 390.652 -63.9445)
				)
			)
		)
		(zone
			(layer "F.Cu")
			(hatch none 0.5)
			(connect_pads
				(clearance 0)
			)
			(min_thickness 0.25)
			(keepout
				(tracks allowed)
				(vias not_allowed)
				(pads allowed)
				(copperpour not_allowed)
				(footprints allowed)
			)
			(placement
				(enabled no)
				(sheetname "")
			)
			(fill
				(thermal_gap 0.5)
				(thermal_bridge_width 0.5)
				(island_removal_mode 0)
			)
			(polygon
				(pts
					(xy 390.652 -63.9445) (xy 390.144 -63.9445) (xy 390.144 -64.3255) (xy 390.652 -64.3255)
				)
			)
		)
	)
	(footprint ""
		(layer "F.Cu")
		(at 419.6207 -104.267 90)
		(property "Reference" "R6W26"
			(at -0.8382 -0.67818 90)
			(unlocked yes)
			(layer "F.SilkS")
			(effects
				(font
					(size 0.4064 0.254)
					(thickness 0.1524)
				)
				(justify left)
			)
		)
		(property "Value" ""
			(at 0 0 90)
			(layer "F.Fab")
			(effects
				(font
					(size 1.27 1.27)
				)
			)
		)
		(duplicate_pad_numbers_are_jumpers no)
		(fp_poly
			(pts
				(xy -0.2794 -0.1016) (xy 0.2794 -0.1016) (xy 0.2794 0.9906) (xy -0.2794 0.9906)
			)
			(stroke
				(width 0)
				(type default)
			)
			(fill no)
			(layer "F.CrtYd")
		)
		(fp_line
			(start 0.2794 -0.1016)
			(end -0.2794 -0.1016)
			(stroke
				(width 0.1)
				(type default)
			)
			(layer "F.Fab")
		)
		(fp_line
			(start -0.2794 -0.1016)
			(end -0.2794 0.9906)
			(stroke
				(width 0.1)
				(type default)
			)
			(layer "F.Fab")
		)
		(fp_line
			(start 0.2794 0.9906)
			(end 0.2794 -0.1016)
			(stroke
				(width 0.1)
				(type default)
			)
			(layer "F.Fab")
		)
		(fp_line
			(start -0.2794 0.9906)
			(end 0.2794 0.9906)
			(stroke
				(width 0.1)
				(type default)
			)
			(layer "F.Fab")
		)
		(pad "1" smd rect
			(at 0 0 90)
			(size 0.508 0.508)
			(layers "F.Cu" "F.Mask" "F.Paste")
			(net "SMB_CPU0_PE_HP_GTL_SCL")
		)
		(pad "2" smd rect
			(at 0 0.889 90)
			(size 0.508 0.508)
			(layers "F.Cu" "F.Mask" "F.Paste")
			(net "SMB_CPU0_PE_HP_GTL_R_SCL")
		)
		(zone
			(layer "F.Cu")
			(hatch none 0.5)
			(connect_pads
				(clearance 0)
			)
			(min_thickness 0.25)
			(keepout
				(tracks allowed)
				(vias not_allowed)
				(pads allowed)
				(copperpour not_allowed)
				(footprints allowed)
			)
			(placement
				(enabled no)
				(sheetname "")
			)
			(fill
				(thermal_gap 0.5)
				(thermal_bridge_width 0.5)
				(island_removal_mode 0)
			)
			(polygon
				(pts
					(xy 419.8747 -104.013) (xy 419.8747 -104.521) (xy 420.2557 -104.521) (xy 420.2557 -104.013)
				)
			)
		)
		(zone
			(layer "F.Cu")
			(hatch none 0.5)
			(connect_pads
				(clearance 0)
			)
			(min_thickness 0.25)
			(keepout
				(tracks not_allowed)
				(vias allowed)
				(pads allowed)
				(copperpour not_allowed)
				(footprints allowed)
			)
			(placement
				(enabled no)
				(sheetname "")
			)
			(fill
				(thermal_gap 0.5)
				(thermal_bridge_width 0.5)
				(island_removal_mode 0)
			)
			(polygon
				(pts
					(xy 420.2557 -104.013) (xy 420.2557 -104.521) (xy 419.8747 -104.521) (xy 419.8747 -104.013)
				)
			)
		)
	)
	(footprint ""
		(layer "F.Cu")
		(at 204.5462 -85.4456 -90)
		(property "Reference" "CT35"
			(at -0.8382 -0.67818 270)
			(unlocked yes)
			(layer "F.SilkS")
			(effects
				(font
					(size 0.4064 0.254)
					(thickness 0.1524)
				)
				(justify left)
			)
		)
		(property "Value" ""
			(at 0 0 270)
			(layer "F.Fab")
			(effects
				(font
					(size 1.27 1.27)
				)
			)
		)
		(duplicate_pad_numbers_are_jumpers no)
		(fp_poly
			(pts
				(xy 0.3048 -0.1016) (xy 0.3048 0.9906) (xy -0.3048 0.9906) (xy -0.3048 -0.1016)
			)
			(stroke
				(width 0)
				(type default)
			)
			(fill no)
			(layer "F.CrtYd")
		)
		(fp_line
			(start -0.3048 0.9906)
			(end 0.3048 0.9906)
			(stroke
				(width 0.1)
				(type default)
			)
			(layer "F.Fab")
		)
		(fp_line
			(start 0.3048 0.9906)
			(end 0.3048 -0.1016)
			(stroke
				(width 0.1)
				(type default)
			)
			(layer "F.Fab")
		)
		(fp_line
			(start -0.3048 -0.1016)
			(end -0.3048 0.9906)
			(stroke
				(width 0.1)
				(type default)
			)
			(layer "F.Fab")
		)
		(fp_line
			(start 0.3048 -0.1016)
			(end -0.3048 -0.1016)
			(stroke
				(width 0.1)
				(type default)
			)
			(layer "F.Fab")
		)
		(pad "1" smd rect
			(at 0 0 270)
			(size 0.508 0.508)
			(layers "F.Cu" "F.Mask" "F.Paste")
			(net "VR_PVCCIN_CPU0_PHASE5")
		)
		(pad "2" smd rect
			(at 0 0.889 270)
			(size 0.508 0.508)
			(layers "F.Cu" "F.Mask" "F.Paste")
			(net "VR_PVCCIN_CPU0_PHASE5_RC")
		)
		(zone
			(layer "F.Cu")
			(hatch none 0.5)
			(connect_pads
				(clearance 0)
			)
			(min_thickness 0.25)
			(keepout
				(tracks not_allowed)
				(vias allowed)
				(pads allowed)
				(copperpour not_allowed)
				(footprints allowed)
			)
			(placement
				(enabled no)
				(sheetname "")
			)
			(fill
				(thermal_gap 0.5)
				(thermal_bridge_width 0.5)
				(island_removal_mode 0)
			)
			(polygon
				(pts
					(xy 203.9112 -85.6996) (xy 203.9112 -85.1916) (xy 204.2922 -85.1916) (xy 204.2922 -85.6996)
				)
			)
		)
		(zone
			(layer "F.Cu")
			(hatch none 0.5)
			(connect_pads
				(clearance 0)
			)
			(min_thickness 0.25)
			(keepout
				(tracks allowed)
				(vias not_allowed)
				(pads allowed)
				(copperpour not_allowed)
				(footprints allowed)
			)
			(placement
				(enabled no)
				(sheetname "")
			)
			(fill
				(thermal_gap 0.5)
				(thermal_bridge_width 0.5)
				(island_removal_mode 0)
			)
			(polygon
				(pts
					(xy 204.2922 -85.6996) (xy 204.2922 -85.1916) (xy 203.9112 -85.1916) (xy 203.9112 -85.6996)
				)
			)
		)
	)
)
